FILE_TYPE = CONNECTIVITY;
{Allegro Design Entry HDL 17.2-2016 S066 (3851973) 4/6/2020}
"PAGE_NUMBER" = 68;
0"NC";
1"SG\g";
2"XP3R3V\g";
3"SG\g";
4"SG\g";
5"SG\g";
6"XP3R3V\g";
7"SG\g";
8"SG\g";
9"XP1R8V_FPGA\g";
10"XP1R2V_FPGA\g";
11"SG\g";
12"SG\g";
13"SG\g";
14"SG\g";
15"SG\g";
16"SG\g";
17"SG\g";
18"XP3R3V\g";
19"XP3R3V\g";
20"SG\g";
21"SG\g";
22"SG\g";
23"XP1R8V_FPGA_PG";
24"XP1R8V_SS";
25"XP1R2V_FB";
26"XP1R2V_EN_R";
27"XP1R2V_SS";
28"XP1R2V_FPGA_PG";
29"XP1R8V_VIN";
30"XP1R8V_PG_R";
31"XP1R8V_EN_R";
32"XP1R2V_FPGA_PG";
33"XP1R2V_PG_R";
34"XP1R2V_VIN";
35"XP1R0V_FPGA_PG";
36"XP1R8V_FB";
%"GND_SG"
"1","(-11900,6850)","0","cls","I1";
;
HDL_POWER"SG"
CDS_LIB"cls"
CDS_LMAN_SYM_OUTLINE"0,0,100,-50"
BODY_TYPE"PLUMBING";
"SGND"22;
%"RESISTOR"
"1","(-6950,7000)","0","passive","I10";
;
$LOCATION"R181"
CDS_LOCATION"R181"
$SEC"1"
CDS_SEC"1"
PACKAGE"0402"
VALUE"0OHM"
CDS_LIB"passive"
CDS_LMAN_SYM_OUTLINE"-50,50,100,-50"
CLS_PN"G155-100R0-J0"
TOLERANCE"-";
"1"
$PN"1"33;
"2"
$PN"2"28;
%"RESISTOR"
"2","(-7600,7300)","0","passive","I11";
;
$LOCATION"R178"
CDS_LOCATION"R178"
$SEC"1"
CDS_SEC"1"
PACKAGE"0402"
VALUE"4.7KOHM"
CLS_PN"G155-14701-01"
CDS_LIB"passive"
CDS_LMAN_SYM_OUTLINE"-50,50,50,-100"
TOLERANCE"1%";
"1"
$PN"1"6;
"2"
$PN"2"33;
%"VCC"
"1","(-7650,7550)","0","cls","I12";
;
VOLTAGE"3.3"
HDL_POWER"XP3R3V"
CDS_LIB"cls"
CDS_LMAN_SYM_OUTLINE"-250,250,250,-250"
BODY_TYPE"PLUMBING";
"$PIN0"6;
%"RESISTOR"
"1","(-6350,7650)","1","passive","I14";
;
$LOCATION"R186"
CDS_LOCATION"R186"
$SEC"1"
CDS_SEC"1"
VALUE"3KOHM"
PACKAGE"0402"
CLS_PN"G155-03001-01"
CDS_LMAN_SYM_OUTLINE"-50,50,100,-50"
CDS_LIB"passive"
TOLERANCE"1%";
"1"
$PN"1"21;
"2"
$PN"2"25;
%"GND_SG"
"1","(-6150,7300)","0","cls","I15";
;
HDL_POWER"SG"
CDS_LMAN_SYM_OUTLINE"0,0,100,-50"
CDS_LIB"cls"
BODY_TYPE"PLUMBING";
"SGND"21;
%"RESISTOR"
"1","(-6100,7650)","1","passive","I16";
;
$LOCATION"R189"
CDS_LOCATION"R189"
$SEC"1"
CDS_SEC"1"
VALUE"3.24KOHM"
NO_ASSY"TRUE"
PACKAGE"0402"
CLS_PN"G155-03241-01"
CDS_LMAN_SYM_OUTLINE"-50,50,100,-50"
CDS_LIB"passive"
TOLERANCE"1%";
"1"
$PN"1"21;
"2"
$PN"2"25;
%"GND_SG"
"1","(-5200,7700)","0","cls","I17";
;
HDL_POWER"SG"
CDS_LMAN_SYM_OUTLINE"0,0,100,-50"
CDS_LIB"cls"
BODY_TYPE"PLUMBING";
"SGND"20;
%"RESISTOR"
"1","(-12450,7750)","0","passive","I18";
;
$LOCATION"R140"
CDS_LOCATION"R140"
$SEC"1"
CDS_SEC"1"
PACKAGE"0402"
VALUE"0OHM"
CLS_PN"G155-100R0-J0"
CDS_LIB"passive"
CDS_LMAN_SYM_OUTLINE"-50,50,100,-50"
TOLERANCE"-";
"1"
$PN"1"35;
"2"
$PN"2"26;
%"RESISTOR"
"2","(-11850,7550)","0","passive","I2";
;
$LOCATION"R165"
CDS_LOCATION"R165"
$SEC"1"
CDS_SEC"1"
PACKAGE"0402"
NO_ASSY"TRUE"
VALUE"10KOHM"
CDS_LIB"passive"
CDS_LMAN_SYM_OUTLINE"-50,50,50,-100"
CLS_PN"G155-11002-01"
TOLERANCE"1%";
"1"
$PN"1"26;
"2"
$PN"2"22;
%"VCC"
"1","(-13350,8950)","0","cls","I20";
;
VOLTAGE"3.3"
HDL_POWER"XP3R3V"
CDS_LIB"cls"
CDS_LMAN_SYM_OUTLINE"-250,250,250,-250"
BODY_TYPE"PLUMBING";
"$PIN0"19;
%"VCC"
"1","(-13250,4000)","0","cls","I24";
;
VOLTAGE"3.3"
HDL_POWER"XP3R3V"
CDS_LIB"cls"
CDS_LMAN_SYM_OUTLINE"-250,250,250,-250"
BODY_TYPE"PLUMBING";
"$PIN0"18;
%"FERRITEBEAD"
"1","(-12500,8800)","0","passive","I25";
;
$LOCATION"L11"
CDS_LOCATION"L11"
$SEC"1"
CDS_SEC"1"
PACKAGE"0603"
VALUE"26OHM"
CLS_PN"G191-10101-01"
CDS_LIB"passive"
CDS_LMAN_SYM_OUTLINE"0,0,200,-100"
TOLERANCE"25%";
"2"
$PN"2"34;
"1"
$PN"1"19;
%"RESISTOR"
"2","(-11700,8300)","0","passive","I26";
;
$LOCATION"R177"
CDS_LOCATION"R177"
$SEC"1"
CDS_SEC"1"
VALUE"1.13KOHM"
NO_ASSY"TRUE"
PACKAGE"0402"
CLS_PN"G152-00055-01"
CDS_LMAN_SYM_OUTLINE"-50,50,50,-100"
CDS_LIB"passive"
TOLERANCE"1%";
"1"
$PN"1"34;
"2"
$PN"2"26;
%"CAPACITOR"
"2","(-11250,8450)","0","passive","I27";
;
$LOCATION"C185"
CDS_LOCATION"C185"
$SEC"1"
CDS_SEC"1"
VOLTAGE"25V"
VALUE"10UF"
PACKAGE"0805"
CDS_LIB"passive"
CDS_LMAN_SYM_OUTLINE"-50,0,50,-50"
TOLERANCE"20%"
CLS_PN"G107-0F106-EM";
"2"
$PN"2"17;
"1"
$PN"1"34;
%"CAPACITOR"
"2","(-11300,7500)","0","passive","I3";
;
$LOCATION"C184"
CDS_LOCATION"C184"
$SEC"1"
CDS_SEC"1"
VALUE"0.1UF"
PACKAGE"0402"
VOLTAGE"25V"
TOLERANCE"10%"
CDS_LMAN_SYM_OUTLINE"-50,0,50,-50"
CDS_LIB"passive"
CLS_PN"G105-0B104-EK";
"2"
$PN"2"22;
"1"
$PN"1"26;
%"GND_SG"
"1","(-10850,8000)","0","cls","I34";
;
VOLTAGE"0"
HDL_POWER"SG"
CDS_LMAN_SYM_OUTLINE"0,0,100,-50"
CDS_LIB"cls"
BODY_TYPE"PLUMBING";
"SGND"17;
%"CAPACITOR"
"2","(-10800,8450)","0","passive","I35";
;
$LOCATION"C188"
CDS_LOCATION"C188"
$SEC"1"
CDS_SEC"1"
VOLTAGE"25V"
PACKAGE"0402"
VALUE"0.1UF"
TOLERANCE"10%"
CLS_PN"G105-0B104-EK"
CDS_LMAN_SYM_OUTLINE"-50,0,50,-50"
CDS_LIB"passive";
"2"
$PN"2"17;
"1"
$PN"1"34;
%"GND_SG"
"1","(-10750,6850)","0","cls","I4";
;
VOLTAGE"0"
HDL_POWER"SG"
CDS_LIB"cls"
CDS_LMAN_SYM_OUTLINE"0,0,100,-50"
BODY_TYPE"PLUMBING";
"SGND"5;
%"GND_SG"
"1","(-11850,1950)","0","cls","I41";
;
HDL_POWER"SG"
CDS_LMAN_SYM_OUTLINE"0,0,100,-50"
CDS_LIB"cls"
BODY_TYPE"PLUMBING";
"SGND"16;
%"RESISTOR"
"1","(-12200,2850)","0","passive","I42";
;
$LOCATION"R141"
CDS_LOCATION"R141"
$SEC"1"
CDS_SEC"1"
PACKAGE"0402"
VALUE"0OHM"
CLS_PN"G155-100R0-J0"
CDS_LIB"passive"
CDS_LMAN_SYM_OUTLINE"-50,50,100,-50"
TOLERANCE"-";
"1"
$PN"1"32;
"2"
$PN"2"31;
%"FERRITEBEAD"
"1","(-12450,3900)","0","passive","I43";
;
$LOCATION"L6"
CDS_LOCATION"L6"
$SEC"1"
CDS_SEC"1"
PACKAGE"0603"
VALUE"26OHM"
CLS_PN"G191-10101-01"
CDS_LIB"passive"
CDS_LMAN_SYM_OUTLINE"0,0,200,-100"
TOLERANCE"25%";
"2"
$PN"2"29;
"1"
$PN"1"18;
%"RESISTOR"
"2","(-11800,2550)","0","passive","I44";
;
$LOCATION"R174"
CDS_LOCATION"R174"
$SEC"1"
CDS_SEC"1"
PACKAGE"0402"
NO_ASSY"TRUE"
VALUE"10KOHM"
CDS_LIB"passive"
CDS_LMAN_SYM_OUTLINE"-50,50,50,-100"
CLS_PN"G155-11002-01"
TOLERANCE"1%";
"1"
$PN"1"31;
"2"
$PN"2"16;
%"RESISTOR"
"2","(-11850,3400)","0","passive","I45";
;
$LOCATION"R166"
CDS_LOCATION"R166"
$SEC"1"
CDS_SEC"1"
PACKAGE"402"
NO_ASSY"TRUE"
VALUE"1.13KOHM"
CDS_LMAN_SYM_OUTLINE"-50,50,50,-100"
CDS_LIB"passive"
CLS_PN"G152-00055-01"
TOLERANCE"1%";
"1"
$PN"1"29;
"2"
$PN"2"31;
%"CAPACITOR"
"2","(-11200,2600)","0","passive","I46";
;
$LOCATION"C187"
CDS_LOCATION"C187"
$SEC"1"
CDS_SEC"1"
VOLTAGE"25V"
VALUE"0.1UF"
PACKAGE"0402"
CLS_PN"G105-0B104-EK"
CDS_LIB"passive"
CDS_LMAN_SYM_OUTLINE"-50,0,50,-50"
TOLERANCE"10%";
"2"
$PN"2"16;
"1"
$PN"1"31;
%"CAPACITOR"
"2","(-11200,3550)","0","passive","I47";
;
$LOCATION"C186"
CDS_LOCATION"C186"
$SEC"1"
CDS_SEC"1"
PACKAGE"0805"
VALUE"10UF"
VOLTAGE"25V"
CDS_LMAN_SYM_OUTLINE"-50,0,50,-50"
CDS_LIB"passive"
TOLERANCE"20%"
CLS_PN"G107-0F106-EM";
"2"
$PN"2"15;
"1"
$PN"1"29;
%"GND_SG"
"1","(-10700,1950)","0","cls","I48";
;
VOLTAGE"0"
HDL_POWER"SG"
CDS_LMAN_SYM_OUTLINE"0,0,100,-50"
CDS_LIB"cls"
BODY_TYPE"PLUMBING";
"SGND"4;
%"CAPACITOR"
"2","(-10650,2350)","0","passive","I49";
;
$LOCATION"C191"
CDS_LOCATION"C191"
$SEC"1"
CDS_SEC"1"
VOLTAGE"25V"
PACKAGE"0201"
VALUE"0.01UF"
CLS_PN"G104-0B103-EK"
CDS_LMAN_SYM_OUTLINE"-50,0,50,-50"
CDS_LIB"passive"
TOLERANCE"10%";
"2"
$PN"2"4;
"1"
$PN"1"24;
%"CAPACITOR"
"2","(-10700,7250)","0","passive","I5";
;
$LOCATION"C190"
CDS_LOCATION"C190"
$SEC"1"
CDS_SEC"1"
VOLTAGE"25V"
PACKAGE"0201"
VALUE"0.01UF"
CLS_PN"G104-0B103-EK"
CDS_LIB"passive"
CDS_LMAN_SYM_OUTLINE"-50,0,50,-50"
TOLERANCE"10%";
"2"
$PN"2"5;
"1"
$PN"1"27;
%"GND_SG"
"1","(-10800,3100)","0","cls","I50";
;
VOLTAGE"0"
HDL_POWER"SG"
CDS_LIB"cls"
CDS_LMAN_SYM_OUTLINE"0,0,100,-50"
BODY_TYPE"PLUMBING";
"SGND"15;
%"CAPACITOR"
"2","(-10750,3550)","0","passive","I51";
;
$LOCATION"C189"
CDS_LOCATION"C189"
$SEC"1"
CDS_SEC"1"
VALUE"0.1UF"
VOLTAGE"25V"
PACKAGE"0402"
CLS_PN"G105-0B104-EK"
CDS_LIB"passive"
CDS_LMAN_SYM_OUTLINE"-50,0,50,-50"
TOLERANCE"10%";
"2"
$PN"2"15;
"1"
$PN"1"29;
%"ISL80101IRAJZ_DFN10"
"1","(-9850,3450)","0","analog","I52";
;
$LOCATION"U21"
CDS_LOCATION"U21"
$SEC"1"
CDS_SEC"1"
PART_NUMBER"ISL80101IRAJZ-T"
CLS_PN"G222-10136-01"
CDS_LMAN_SYM_OUTLINE"0,0,900,-1000"
CDS_LIB"analog"
CDS_PHYS_PART_NAME"ISL80101IRAJZ_DFN10-G222-10136A";
"THRM_PAD"
$PN"11"13;
"VIN_2"
$PN"10"29;
"VIN_1"
$PN"9"29;
"NC"
$PN"8"0;
"ENABLE"
$PN"7"31;
"SS"
$PN"6"24;
"GND"
$PN"5"13;
"PG"
$PN"4"30;
"SENSE/ADJ"
$PN"3"36;
"VOUT_2"
$PN"2"9;
"VOUT_1"
$PN"1"9;
%"RESISTOR"
"2","(-6400,8350)","0","passive","I59";
;
$LOCATION"R185"
CDS_LOCATION"R185"
$SEC"1"
CDS_SEC"1"
VALUE"4.22KOHM"
PACKAGE"0402"
TOLERANCE"1%"
CLS_PN"G155-04221-01"
CDS_PHYS_PART_NAME"RESISTOR-G155-02871-01,2.87KOHB"
CDS_LMAN_SYM_OUTLINE"-50,50,50,-100"
CDS_LIB"passive";
"1"
$PN"1"10;
"2"
$PN"2"25;
%"ISL80101IRAJZ_DFN10"
"1","(-9900,8350)","0","analog","I6";
;
$LOCATION"U20"
CDS_LOCATION"U20"
$SEC"1"
CDS_SEC"1"
CLS_PN"G222-10136-01"
PART_NUMBER"ISL80101IRAJZ-T"
CDS_LMAN_SYM_OUTLINE"0,0,900,-1000"
CDS_LIB"analog"
CDS_PHYS_PART_NAME"ISL80101IRAJZ_DFN10-G222-10136A";
"THRM_PAD"
$PN"11"14;
"VIN_2"
$PN"10"34;
"VIN_1"
$PN"9"34;
"NC"
$PN"8"0;
"ENABLE"
$PN"7"26;
"SS"
$PN"6"27;
"GND"
$PN"5"14;
"PG"
$PN"4"33;
"SENSE/ADJ"
$PN"3"25;
"VOUT_2"
$PN"2"10;
"VOUT_1"
$PN"1"10;
%"CAPACITOR"
"2","(-5750,8350)","0","passive","I60";
;
$LOCATION"C194"
CDS_LOCATION"C194"
$SEC"1"
CDS_SEC"1"
VALUE"10UF"
VOLTAGE"25V"
PACKAGE"0805"
CDS_LMAN_SYM_OUTLINE"-50,0,50,-50"
CDS_LIB"passive"
TOLERANCE"20%"
CLS_PN"G107-0F106-EM";
"2"
$PN"2"20;
"1"
$PN"1"10;
%"CAPACITOR"
"2","(-5150,8350)","0","passive","I61";
;
$LOCATION"C196"
CDS_LOCATION"C196"
$SEC"1"
CDS_SEC"1"
PACKAGE"0402"
VOLTAGE"25V"
VALUE"0.1UF"
TOLERANCE"10%"
CDS_LIB"passive"
CDS_LMAN_SYM_OUTLINE"-50,0,50,-50"
CLS_PN"G105-0B104-EK";
"2"
$PN"2"20;
"1"
$PN"1"10;
%"GND_SG"
"1","(-8650,6700)","0","cls","I7";
;
VOLTAGE"0"
HDL_POWER"SG"
CDS_LMAN_SYM_OUTLINE"0,0,100,-50"
CDS_LIB"cls"
BODY_TYPE"PLUMBING";
"SGND"14;
%"GND_SG"
"1","(-8600,1800)","0","cls","I70";
;
VOLTAGE"0"
HDL_POWER"SG"
CDS_LIB"cls"
CDS_LMAN_SYM_OUTLINE"0,0,100,-50"
BODY_TYPE"PLUMBING";
"SGND"13;
%"CAPACITOR"
"2","(-7650,1900)","0","passive","I71";
;
$LOCATION"C193"
CDS_LOCATION"C193"
$SEC"1"
CDS_SEC"1"
VOLTAGE"25V"
PACKAGE"0201"
VALUE"0.01UF"
CLS_PN"G104-0B103-EK"
TOLERANCE"10%"
CDS_LIB"passive"
CDS_LMAN_SYM_OUTLINE"-50,0,50,-50";
"2"
$PN"2"3;
"1"
$PN"1"30;
%"GND_SG"
"1","(-7700,1650)","0","cls","I72";
;
VOLTAGE"0"
HDL_POWER"SG"
CDS_LMAN_SYM_OUTLINE"0,0,100,-50"
CDS_LIB"cls"
BODY_TYPE"PLUMBING";
"SGND"3;
%"RESISTOR"
"2","(-7600,2400)","0","passive","I73";
;
$LOCATION"R179"
CDS_LOCATION"R179"
$SEC"1"
CDS_SEC"1"
VALUE"4.7KOHM"
PACKAGE"0402"
CDS_LMAN_SYM_OUTLINE"-50,50,50,-100"
CDS_LIB"passive"
CLS_PN"G155-14701-01"
TOLERANCE"1%";
"1"
$PN"1"2;
"2"
$PN"2"30;
%"RESISTOR"
"1","(-7000,2100)","0","passive","I74";
;
$LOCATION"R182"
CDS_LOCATION"R182"
$SEC"1"
CDS_SEC"1"
VALUE"0OHM"
PACKAGE"0402"
CDS_LIB"passive"
CDS_LMAN_SYM_OUTLINE"-50,50,100,-50"
CLS_PN"G155-100R0-J0"
TOLERANCE"-";
"1"
$PN"1"30;
"2"
$PN"2"23;
%"VCC"
"1","(-7650,2650)","0","cls","I75";
;
HDL_POWER"XP3R3V"
VOLTAGE"3.3"
CDS_LMAN_SYM_OUTLINE"-250,250,250,-250"
CDS_LIB"cls"
BODY_TYPE"PLUMBING";
"$PIN0"2;
%"GND_SG"
"1","(-6100,2400)","0","cls","I77";
;
HDL_POWER"SG"
CDS_LIB"cls"
CDS_LMAN_SYM_OUTLINE"0,0,100,-50"
BODY_TYPE"PLUMBING";
"SGND"12;
%"RESISTOR"
"2","(-6350,3450)","0","passive","I78";
;
$LOCATION"R187"
CDS_LOCATION"R187"
$SEC"1"
CDS_SEC"1"
VALUE"4.22KOHM"
PACKAGE"0402"
TOLERANCE"1%"
CDS_LIB"passive"
CDS_LMAN_SYM_OUTLINE"-50,50,50,-100"
CDS_PHYS_PART_NAME"RESISTOR-G155-02871-01,2.87KOHB"
CLS_PN"G155-04221-01";
"1"
$PN"1"9;
"2"
$PN"2"36;
%"RESISTOR"
"1","(-6300,2750)","1","passive","I79";
;
$LOCATION"R188"
CDS_LOCATION"R188"
$SEC"1"
CDS_SEC"1"
PACKAGE"0402"
VALUE"3.24KOHM"
CDS_LMAN_SYM_OUTLINE"-50,50,100,-50"
CDS_LIB"passive"
CLS_PN"G155-03241-01"
TOLERANCE"1%";
"1"
$PN"1"12;
"2"
$PN"2"36;
%"GND_SG"
"1","(-7700,6550)","0","cls","I8";
;
VOLTAGE"0"
HDL_POWER"SG"
CDS_LIB"cls"
CDS_LMAN_SYM_OUTLINE"0,0,100,-50"
BODY_TYPE"PLUMBING";
"SGND"1;
%"RESISTOR"
"1","(-6050,2750)","1","passive","I80";
;
$LOCATION"R190"
CDS_LOCATION"R190"
$SEC"1"
CDS_SEC"1"
PACKAGE"0402"
VALUE"3.24KOHM"
CDS_LIB"passive"
CDS_LMAN_SYM_OUTLINE"-50,50,100,-50"
CLS_PN"G155-03241-01"
TOLERANCE"1%";
"1"
$PN"1"12;
"2"
$PN"2"36;
%"CAPACITOR"
"2","(-5700,3450)","0","passive","I81";
;
$LOCATION"C195"
CDS_LOCATION"C195"
$SEC"1"
CDS_SEC"1"
VOLTAGE"25V"
PACKAGE"0805"
VALUE"10UF"
CDS_LIB"passive"
CDS_LMAN_SYM_OUTLINE"-50,0,50,-50"
TOLERANCE"20%"
CLS_PN"G107-0F106-EM";
"2"
$PN"2"11;
"1"
$PN"1"9;
%"GND_SG"
"1","(-5150,2900)","0","cls","I82";
;
HDL_POWER"SG"
CDS_LIB"cls"
CDS_LMAN_SYM_OUTLINE"0,0,100,-50"
BODY_TYPE"PLUMBING";
"SGND"11;
%"CAPACITOR"
"2","(-5100,3450)","0","passive","I83";
;
$LOCATION"C197"
CDS_LOCATION"C197"
$SEC"1"
CDS_SEC"1"
PACKAGE"0402"
VOLTAGE"25V"
VALUE"0.1UF"
CLS_PN"G105-0B104-EK"
CDS_LIB"passive"
CDS_LMAN_SYM_OUTLINE"-50,0,50,-50"
TOLERANCE"10%";
"2"
$PN"2"11;
"1"
$PN"1"9;
%"VCC"
"1","(-4350,8900)","0","cls","I84";
;
VOLTAGE"1.2V"
HDL_POWER"XP1R2V_FPGA"
CDS_LMAN_SYM_OUTLINE"-250,250,250,-250"
CDS_LIB"cls"
BODY_TYPE"PLUMBING";
"$PIN0"10;
%"VCC"
"1","(-4200,4100)","0","cls","I86";
;
VOLTAGE"1.8V"
HDL_POWER"XP1R8V_FPGA"
CDS_LIB"cls"
CDS_LMAN_SYM_OUTLINE"-250,250,250,-250"
BODY_TYPE"PLUMBING";
"$PIN0"9;
%"CAPACITOR"
"2","(-7650,6800)","0","passive","I9";
;
$LOCATION"C192"
CDS_LOCATION"C192"
$SEC"1"
CDS_SEC"1"
VALUE"0.01UF"
VOLTAGE"25V"
PACKAGE"0201"
CDS_LIB"passive"
CDS_LMAN_SYM_OUTLINE"-50,0,50,-50"
TOLERANCE"10%"
CLS_PN"G104-0B103-EK";
"2"
$PN"2"1;
"1"
$PN"1"33;
%"CAPACITOR"
"2","(-13200,8450)","0","passive","I93";
;
$LOCATION"C180"
CDS_LOCATION"C180"
$SEC"1"
CDS_SEC"1"
VOLTAGE"10V"
PACKAGE"0805"
VALUE"22UF"
CDS_LIB"passive"
CDS_LMAN_SYM_OUTLINE"-50,0,50,-50"
CLS_PN"G107-0F226-CM"
TOLERANCE"20%";
"2"
$PN"2"8;
"1"
$PN"1"19;
%"CAPACITOR"
"2","(-12750,8450)","0","passive","I94";
;
$LOCATION"C182"
CDS_LOCATION"C182"
$SEC"1"
CDS_SEC"1"
VOLTAGE"25V"
VALUE"0.1UF"
PACKAGE"0402"
TOLERANCE"10%"
CLS_PN"G105-0B104-EK"
CDS_LMAN_SYM_OUTLINE"-50,0,50,-50"
CDS_LIB"passive";
"2"
$PN"2"8;
"1"
$PN"1"19;
%"GND_SG"
"1","(-12800,8100)","0","cls","I95";
;
HDL_POWER"SG"
CDS_LMAN_SYM_OUTLINE"0,0,100,-50"
CDS_LIB"cls"
BODY_TYPE"PLUMBING";
"SGND"8;
%"GND_SG"
"1","(-12700,3200)","0","cls","I96";
;
HDL_POWER"SG"
CDS_LMAN_SYM_OUTLINE"0,0,100,-50"
CDS_LIB"cls"
BODY_TYPE"PLUMBING";
"SGND"7;
%"CAPACITOR"
"2","(-13100,3550)","0","passive","I97";
;
$LOCATION"C181"
CDS_LOCATION"C181"
$SEC"1"
CDS_SEC"1"
PACKAGE"0805"
VALUE"22UF"
VOLTAGE"10V"
CDS_LIB"passive"
CDS_LMAN_SYM_OUTLINE"-50,0,50,-50"
CLS_PN"G107-0F226-CM"
TOLERANCE"20%";
"2"
$PN"2"7;
"1"
$PN"1"18;
%"CAPACITOR"
"2","(-12650,3550)","0","passive","I98";
;
$LOCATION"C183"
CDS_LOCATION"C183"
$SEC"1"
CDS_SEC"1"
VOLTAGE"25V"
VALUE"0.1UF"
PACKAGE"0402"
CDS_LIB"passive"
CDS_LMAN_SYM_OUTLINE"-50,0,50,-50"
MATERIAL"X7R"
CLS_PN"G105-0B104-EK"
TOLERANCE"10%";
"2"
$PN"2"7;
"1"
$PN"1"18;
END.
